# T6G (Grand Teton) — schematic netlist excerpt (pin names and nets, part order shuffled) for the footprints in the layout excerpt that follows; sources: Cadence DE-HDL packaged netlist, KiCad conversion of 04192023_DAF0TMB3IC0_F0TG_MB_C_brd_V02_OCP.brd

PC6615_1  Q_CAP  22UF 16V 20% X6S  pkg C0805  page 365 : A = SW_P12V_AUX_P0V9_RETIMER_CPU1_FLT ; B = GND
C2597  Q_CAP  22UF 4V 20% X6S  pkg C0402  page 70 : A = PVDDIO_P0 ; B = GND
C1237  Q_CAP  0.1UF 25V 10% X7R  pkg 0402  page 131 : A = P3V3_OCP_SFF ; B = GND

(kicad_pcb
	(version 20260206)
	(generator "pcbnew")
	(generator_version "10.0")
	(general
		(thickness 1.6)
		(legacy_teardrops no)
	)
	(paper "A4")
	(title_block
		(title "04192023_DAF0TMB3IC0_F0TG_MB_C_brd_V02_OCP.brd")
		(comment 1 "Grand Teton / footprints 5116-5118 of 8354")
	)
	(layers
		(0 "F.Cu" signal "TOP")
		(4 "In1.Cu" signal "GND")
		(6 "In2.Cu" signal "IN1")
		(8 "In3.Cu" signal "GND1")
		(10 "In4.Cu" signal "IN2")
		(12 "In5.Cu" signal "GND2")
		(14 "In6.Cu" signal "IN3")
		(16 "In7.Cu" signal "GND3")
		(18 "In8.Cu" signal "VCC")
		(20 "In9.Cu" signal "VCC1")
		(22 "In10.Cu" signal "GND4")
		(24 "In11.Cu" signal "IN4")
		(26 "In12.Cu" signal "GND5")
		(28 "In13.Cu" signal "IN5")
		(30 "In14.Cu" signal "GND6")
		(32 "In15.Cu" signal "IN6")
		(34 "In16.Cu" signal "GND7")
		(2 "B.Cu" signal "BOTTOM")
		(9 "F.Adhes" user "F.Adhesive")
		(11 "B.Adhes" user "B.Adhesive")
		(13 "F.Paste" user "Package Geometry/Pastemask Top")
		(15 "B.Paste" user "Package Geometry/Pastemask Bottom")
		(5 "F.SilkS" user "Ref Des/Silkscreen Top")
		(7 "B.SilkS" user "Ref Des/Silkscreen Bottom")
		(1 "F.Mask" user "Board Geometry/Soldermask Top")
		(3 "B.Mask" user "Board Geometry/Soldermask Bottom")
		(17 "Dwgs.User" user "User.Drawings")
		(19 "Cmts.User" user "User.Comments")
		(21 "Eco1.User" user "User.Eco1")
		(23 "Eco2.User" user "User.Eco2")
		(25 "Edge.Cuts" user "Board Geometry/Outline")
		(27 "Margin" user)
		(31 "F.CrtYd" user "Package Geometry/Place Bound Top")
		(29 "B.CrtYd" user "Package Geometry/Place Bound Bottom")
		(35 "F.Fab" user "Ref Des/Assembly Top")
		(33 "B.Fab" user "Ref Des/Assembly Bottom")
	)
	(footprint ""
		(layer "B.Cu")
		(at 435.549802 -13.120116 180)
		(property "Reference" "C1237"
			(at 0 0 0)
			(layer "B.SilkS")
			(hide yes)
			(effects
				(font
					(size 1.27 1.27)
				)
				(justify mirror)
			)
		)
		(property "Value" ""
			(at 0 0 0)
			(layer "B.Fab")
			(effects
				(font
					(size 1.27 1.27)
				)
				(justify mirror)
			)
		)
		(duplicate_pad_numbers_are_jumpers no)
		(fp_line
			(start 0.7874 0.4064)
			(end 0.7874 -0.4064)
			(stroke
				(width 0.1524)
				(type default)
			)
			(layer "B.SilkS")
		)
		(fp_line
			(start 0.7874 -0.4064)
			(end -0.7874 -0.4064)
			(stroke
				(width 0.1524)
				(type default)
			)
			(layer "B.SilkS")
		)
		(fp_line
			(start -0.7874 0.4064)
			(end 0.7874 0.4064)
			(stroke
				(width 0.1524)
				(type default)
			)
			(layer "B.SilkS")
		)
		(fp_line
			(start -0.7874 -0.4064)
			(end -0.7874 0.4064)
			(stroke
				(width 0.1524)
				(type default)
			)
			(layer "B.SilkS")
		)
		(fp_line
			(start 0.67945 0.3048)
			(end 0.67945 -0.305054)
			(stroke
				(width 0.1)
				(type default)
			)
			(layer "B.Fab")
		)
		(fp_line
			(start 0.67945 -0.305054)
			(end 0.12065 -0.305054)
			(stroke
				(width 0.1)
				(type default)
			)
			(layer "B.Fab")
		)
		(fp_line
			(start 0.12065 0.3048)
			(end 0.67945 0.3048)
			(stroke
				(width 0.1)
				(type default)
			)
			(layer "B.Fab")
		)
		(fp_line
			(start 0.12065 0.2794)
			(end 0.12065 0.3048)
			(stroke
				(width 0.1)
				(type default)
			)
			(layer "B.Fab")
		)
		(fp_line
			(start 0.12065 -0.2794)
			(end -0.12065 -0.2794)
			(stroke
				(width 0.1)
				(type default)
			)
			(layer "B.Fab")
		)
		(fp_line
			(start 0.12065 -0.305054)
			(end 0.12065 -0.2794)
			(stroke
				(width 0.1)
				(type default)
			)
			(layer "B.Fab")
		)
		(fp_line
			(start -0.120396 0.3048)
			(end -0.120396 0.2794)
			(stroke
				(width 0.1)
				(type default)
			)
			(layer "B.Fab")
		)
		(fp_line
			(start -0.120396 0.2794)
			(end 0.12065 0.2794)
			(stroke
				(width 0.1)
				(type default)
			)
			(layer "B.Fab")
		)
		(fp_line
			(start -0.12065 -0.2794)
			(end -0.12065 -0.3048)
			(stroke
				(width 0.1)
				(type default)
			)
			(layer "B.Fab")
		)
		(fp_line
			(start -0.12065 -0.3048)
			(end -0.67945 -0.3048)
			(stroke
				(width 0.1)
				(type default)
			)
			(layer "B.Fab")
		)
		(fp_line
			(start -0.67945 0.3048)
			(end -0.120396 0.3048)
			(stroke
				(width 0.1)
				(type default)
			)
			(layer "B.Fab")
		)
		(fp_line
			(start -0.67945 -0.3048)
			(end -0.67945 0.3048)
			(stroke
				(width 0.1)
				(type default)
			)
			(layer "B.Fab")
		)
		(pad "1" smd circle
			(at 0.40005 0)
			(size 0 0)
			(layers "B.Cu" "B.Mask" "B.Paste")
			(net "P3V3_OCP_SFF")
		)
		(pad "2" smd circle
			(at -0.40005 0)
			(size 0 0)
			(layers "B.Cu" "B.Mask" "B.Paste")
			(net "GND")
		)
	)
	(footprint ""
		(layer "B.Cu")
		(at 17.90065 -388.789926 90)
		(property "Reference" "PC6615_1"
			(at 0 0 90)
			(layer "B.SilkS")
			(hide yes)
			(effects
				(font
					(size 1.27 1.27)
				)
				(justify mirror)
			)
		)
		(property "Value" ""
			(at 0 0 90)
			(layer "B.Fab")
			(effects
				(font
					(size 1.27 1.27)
				)
				(justify mirror)
			)
		)
		(duplicate_pad_numbers_are_jumpers no)
		(fp_line
			(start 1.524 -0.762)
			(end -1.524 -0.762)
			(stroke
				(width 0.1524)
				(type default)
			)
			(layer "B.SilkS")
		)
		(fp_line
			(start -1.524 -0.762)
			(end -1.524 0.762)
			(stroke
				(width 0.1524)
				(type default)
			)
			(layer "B.SilkS")
		)
		(fp_line
			(start 1.524 0.762)
			(end 1.524 -0.762)
			(stroke
				(width 0.1524)
				(type default)
			)
			(layer "B.SilkS")
		)
		(fp_line
			(start -1.524 0.762)
			(end 1.524 0.762)
			(stroke
				(width 0.1524)
				(type default)
			)
			(layer "B.SilkS")
		)
		(fp_line
			(start 1.1049 -0.724916)
			(end 1.1049 0.724916)
			(stroke
				(width 0.1)
				(type default)
			)
			(layer "B.Fab")
		)
		(fp_line
			(start -1.1049 -0.724916)
			(end 1.1049 -0.724916)
			(stroke
				(width 0.1)
				(type default)
			)
			(layer "B.Fab")
		)
		(fp_line
			(start 1.1049 0.724916)
			(end -1.1049 0.724916)
			(stroke
				(width 0.1)
				(type default)
			)
			(layer "B.Fab")
		)
		(fp_line
			(start -1.1049 0.724916)
			(end -1.1049 -0.724916)
			(stroke
				(width 0.1)
				(type default)
			)
			(layer "B.Fab")
		)
		(pad "1" smd rect
			(at 0.889 0 90)
			(size 1.016 1.27)
			(layers "B.Cu" "B.Mask" "B.Paste")
			(net "SW_P12V_AUX_P0V9_RETIMER_CPU1_FLT")
		)
		(pad "2" smd rect
			(at -0.889 0 90)
			(size 1.016 1.27)
			(layers "B.Cu" "B.Mask" "B.Paste")
			(net "GND")
		)
	)
	(footprint ""
		(layer "B.Cu")
		(at 348.151958 -263.521952)
		(property "Reference" "C2597"
			(at 0 0 0)
			(layer "B.SilkS")
			(hide yes)
			(effects
				(font
					(size 1.27 1.27)
				)
				(justify mirror)
			)
		)
		(property "Value" ""
			(at 0 0 0)
			(layer "B.Fab")
			(effects
				(font
					(size 1.27 1.27)
				)
				(justify mirror)
			)
		)
		(duplicate_pad_numbers_are_jumpers no)
		(fp_line
			(start -0.7874 -0.4064)
			(end -0.7874 0.4064)
			(stroke
				(width 0.1524)
				(type default)
			)
			(layer "B.SilkS")
		)
		(fp_line
			(start -0.7874 0.4064)
			(end 0.7874 0.4064)
			(stroke
				(width 0.1524)
				(type default)
			)
			(layer "B.SilkS")
		)
		(fp_line
			(start 0.7874 -0.4064)
			(end -0.7874 -0.4064)
			(stroke
				(width 0.1524)
				(type default)
			)
			(layer "B.SilkS")
		)
		(fp_line
			(start 0.7874 0.4064)
			(end 0.7874 -0.4064)
			(stroke
				(width 0.1524)
				(type default)
			)
			(layer "B.SilkS")
		)
		(fp_line
			(start -0.67945 -0.3048)
			(end -0.67945 0.3048)
			(stroke
				(width 0.1)
				(type default)
			)
			(layer "B.Fab")
		)
		(fp_line
			(start -0.67945 0.3048)
			(end -0.120396 0.3048)
			(stroke
				(width 0.1)
				(type default)
			)
			(layer "B.Fab")
		)
		(fp_line
			(start -0.12065 -0.3048)
			(end -0.67945 -0.3048)
			(stroke
				(width 0.1)
				(type default)
			)
			(layer "B.Fab")
		)
		(fp_line
			(start -0.12065 -0.2794)
			(end -0.12065 -0.3048)
			(stroke
				(width 0.1)
				(type default)
			)
			(layer "B.Fab")
		)
		(fp_line
			(start -0.120396 0.2794)
			(end 0.12065 0.2794)
			(stroke
				(width 0.1)
				(type default)
			)
			(layer "B.Fab")
		)
		(fp_line
			(start -0.120396 0.3048)
			(end -0.120396 0.2794)
			(stroke
				(width 0.1)
				(type default)
			)
			(layer "B.Fab")
		)
		(fp_line
			(start 0.12065 -0.305054)
			(end 0.12065 -0.2794)
			(stroke
				(width 0.1)
				(type default)
			)
			(layer "B.Fab")
		)
		(fp_line
			(start 0.12065 -0.2794)
			(end -0.12065 -0.2794)
			(stroke
				(width 0.1)
				(type default)
			)
			(layer "B.Fab")
		)
		(fp_line
			(start 0.12065 0.2794)
			(end 0.12065 0.3048)
			(stroke
				(width 0.1)
				(type default)
			)
			(layer "B.Fab")
		)
		(fp_line
			(start 0.12065 0.3048)
			(end 0.67945 0.3048)
			(stroke
				(width 0.1)
				(type default)
			)
			(layer "B.Fab")
		)
		(fp_line
			(start 0.67945 -0.305054)
			(end 0.12065 -0.305054)
			(stroke
				(width 0.1)
				(type default)
			)
			(layer "B.Fab")
		)
		(fp_line
			(start 0.67945 0.3048)
			(end 0.67945 -0.305054)
			(stroke
				(width 0.1)
				(type default)
			)
			(layer "B.Fab")
		)
		(pad "1" smd circle
			(at 0.40005 0 180)
			(size 0 0)
			(layers "B.Cu" "B.Mask" "B.Paste")
			(net "PVDDIO_P0")
		)
		(pad "2" smd circle
			(at -0.40005 0 180)
			(size 0 0)
			(layers "B.Cu" "B.Mask" "B.Paste")
			(net "GND")
		)
	)
)
